FILE_TYPE = CONNECTIVITY;
{Concept-HDL 13.60-s021 22-Mar-2001}
0"NC";
1"G\I";
2"P3V3_AUX \G";
%"SYNONYM"
"1","(1850,2050)","0","dev_standard","4P";
;
NEEDS_NO_SIZE"TRUE"
BODY_TYPE"PLUMBING"
CDS_LIB"dev_standard";
"A\NWC\NAC"1;
"A\NWC\NAC"2;
%"DRAWING"
"2","(1275,1750)","0","dev_standard","";
;
LAST_MODIFIED"Wed Mar 13 09:19:45 2002"
TITLE"P3V3_AUX"
ABBREV"P3V3_AUX";
END.
